# S9S_MB_2U (Grand Teton) — schematic netlist excerpt (pin names and nets, part order shuffled) for the footprints in the layout excerpt that follows; sources: Cadence DE-HDL packaged netlist, KiCad conversion of 03242023_DA0F0TMBIJ0_F0T_Motherboard_J_brd_V01_OCP.brd

C66  Q_CAP  10UF 16V 10% X6S  pkg C0805  page 103 : A = P12V_S3_AUX_CPU1_NVDIMM ; B = GND
R3325  Q_RES  10K 1% CHIP  pkg 0402LF  page 198 : A = FM_PCH_SPKR ; B = GND
C1830  Q_CAP  22UF 16V 20% X6S  pkg C0805  page 159 : A = P12V_OCP_V3_2 ; B = GND

(kicad_pcb
	(version 20260206)
	(generator "pcbnew")
	(generator_version "10.0")
	(general
		(thickness 1.6)
		(legacy_teardrops no)
	)
	(paper "A4")
	(title_block
		(title "03242023_DA0F0TMBIJ0_F0T_Motherboard_J_brd_V01_OCP.brd")
		(comment 1 "Grand Teton / footprints 5427-5429 of 6105")
	)
	(layers
		(0 "F.Cu" signal "TOP")
		(4 "In1.Cu" signal "GND")
		(6 "In2.Cu" signal "IN1")
		(8 "In3.Cu" signal "GND1")
		(10 "In4.Cu" signal "IN2")
		(12 "In5.Cu" signal "GND2")
		(14 "In6.Cu" signal "IN3")
		(16 "In7.Cu" signal "GND3")
		(18 "In8.Cu" signal "VCC")
		(20 "In9.Cu" signal "VCC1")
		(22 "In10.Cu" signal "GND4")
		(24 "In11.Cu" signal "IN4")
		(26 "In12.Cu" signal "GND5")
		(28 "In13.Cu" signal "IN5")
		(30 "In14.Cu" signal "GND6")
		(32 "In15.Cu" signal "IN6")
		(34 "In16.Cu" signal "GND7")
		(2 "B.Cu" signal "BOTTOM")
		(9 "F.Adhes" user "F.Adhesive")
		(11 "B.Adhes" user "B.Adhesive")
		(13 "F.Paste" user "Package Geometry/Pastemask Top")
		(15 "B.Paste" user "Package Geometry/Pastemask Bottom")
		(5 "F.SilkS" user "Ref Des/Silkscreen Top")
		(7 "B.SilkS" user "Ref Des/Silkscreen Bottom")
		(1 "F.Mask" user "Board Geometry/Soldermask Top")
		(3 "B.Mask" user "Board Geometry/Soldermask Bottom")
		(17 "Dwgs.User" user "User.Drawings")
		(19 "Cmts.User" user "User.Comments")
		(21 "Eco1.User" user "User.Eco1")
		(23 "Eco2.User" user "User.Eco2")
		(25 "Edge.Cuts" user "Board Geometry/Outline")
		(27 "Margin" user)
		(31 "F.CrtYd" user "Package Geometry/Place Bound Top")
		(29 "B.CrtYd" user "Package Geometry/Place Bound Bottom")
		(35 "F.Fab" user "Ref Des/Assembly Top")
		(33 "B.Fab" user "Ref Des/Assembly Bottom")
	)
	(footprint ""
		(layer "B.Cu")
		(at 65.90411 -17.941544)
		(property "Reference" "C1830"
			(at 0 0 0)
			(layer "B.SilkS")
			(hide yes)
			(effects
				(font
					(size 1.27 1.27)
				)
				(justify mirror)
			)
		)
		(property "Value" ""
			(at 0 0 0)
			(layer "B.Fab")
			(effects
				(font
					(size 1.27 1.27)
				)
				(justify mirror)
			)
		)
		(duplicate_pad_numbers_are_jumpers no)
		(fp_line
			(start -1.524 -0.762)
			(end -1.524 0.762)
			(stroke
				(width 0.1524)
				(type default)
			)
			(layer "B.SilkS")
		)
		(fp_line
			(start -1.524 0.762)
			(end 1.524 0.762)
			(stroke
				(width 0.1524)
				(type default)
			)
			(layer "B.SilkS")
		)
		(fp_line
			(start 1.524 -0.762)
			(end -1.524 -0.762)
			(stroke
				(width 0.1524)
				(type default)
			)
			(layer "B.SilkS")
		)
		(fp_line
			(start 1.524 0.762)
			(end 1.524 -0.762)
			(stroke
				(width 0.1524)
				(type default)
			)
			(layer "B.SilkS")
		)
		(fp_line
			(start -1.1049 -0.724916)
			(end 1.1049 -0.724916)
			(stroke
				(width 0.1)
				(type default)
			)
			(layer "B.Fab")
		)
		(fp_line
			(start -1.1049 0.724916)
			(end -1.1049 -0.724916)
			(stroke
				(width 0.1)
				(type default)
			)
			(layer "B.Fab")
		)
		(fp_line
			(start 1.1049 -0.724916)
			(end 1.1049 0.724916)
			(stroke
				(width 0.1)
				(type default)
			)
			(layer "B.Fab")
		)
		(fp_line
			(start 1.1049 0.724916)
			(end -1.1049 0.724916)
			(stroke
				(width 0.1)
				(type default)
			)
			(layer "B.Fab")
		)
		(pad "1" smd rect
			(at 0.889 0)
			(size 1.016 1.27)
			(layers "B.Cu" "B.Mask" "B.Paste")
			(net "P12V_OCP_V3_2")
		)
		(pad "2" smd rect
			(at -0.889 0)
			(size 1.016 1.27)
			(layers "B.Cu" "B.Mask" "B.Paste")
			(net "GND")
		)
	)
	(footprint ""
		(layer "B.Cu")
		(at 34.848546 -321.554856 -90)
		(property "Reference" "C66"
			(at 0 0 90)
			(layer "B.SilkS")
			(hide yes)
			(effects
				(font
					(size 1.27 1.27)
				)
				(justify mirror)
			)
		)
		(property "Value" ""
			(at 0 0 90)
			(layer "B.Fab")
			(effects
				(font
					(size 1.27 1.27)
				)
				(justify mirror)
			)
		)
		(duplicate_pad_numbers_are_jumpers no)
		(fp_line
			(start -1.524 0.762)
			(end 1.524 0.762)
			(stroke
				(width 0.1524)
				(type default)
			)
			(layer "B.SilkS")
		)
		(fp_line
			(start 1.524 0.762)
			(end 1.524 -0.762)
			(stroke
				(width 0.1524)
				(type default)
			)
			(layer "B.SilkS")
		)
		(fp_line
			(start -1.524 -0.762)
			(end -1.524 0.762)
			(stroke
				(width 0.1524)
				(type default)
			)
			(layer "B.SilkS")
		)
		(fp_line
			(start 1.524 -0.762)
			(end -1.524 -0.762)
			(stroke
				(width 0.1524)
				(type default)
			)
			(layer "B.SilkS")
		)
		(fp_line
			(start -1.1049 0.724916)
			(end -1.1049 -0.724916)
			(stroke
				(width 0.1)
				(type default)
			)
			(layer "B.Fab")
		)
		(fp_line
			(start 1.1049 0.724916)
			(end -1.1049 0.724916)
			(stroke
				(width 0.1)
				(type default)
			)
			(layer "B.Fab")
		)
		(fp_line
			(start -1.1049 -0.724916)
			(end 1.1049 -0.724916)
			(stroke
				(width 0.1)
				(type default)
			)
			(layer "B.Fab")
		)
		(fp_line
			(start 1.1049 -0.724916)
			(end 1.1049 0.724916)
			(stroke
				(width 0.1)
				(type default)
			)
			(layer "B.Fab")
		)
		(pad "1" smd rect
			(at 0.889 0 270)
			(size 1.016 1.27)
			(layers "B.Cu" "B.Mask" "B.Paste")
			(net "P12V_S3_AUX_CPU1_NVDIMM")
		)
		(pad "2" smd rect
			(at -0.889 0 270)
			(size 1.016 1.27)
			(layers "B.Cu" "B.Mask" "B.Paste")
			(net "GND")
		)
	)
	(footprint ""
		(layer "B.Cu")
		(at 337.552284 -33.72612 90)
		(property "Reference" "R3325"
			(at 0 0 90)
			(layer "B.SilkS")
			(hide yes)
			(effects
				(font
					(size 1.27 1.27)
				)
				(justify mirror)
			)
		)
		(property "Value" ""
			(at 0 0 90)
			(layer "B.Fab")
			(effects
				(font
					(size 1.27 1.27)
				)
				(justify mirror)
			)
		)
		(duplicate_pad_numbers_are_jumpers no)
		(fp_line
			(start 0.7874 -0.4064)
			(end -0.7874 -0.4064)
			(stroke
				(width 0.1524)
				(type default)
			)
			(layer "B.SilkS")
		)
		(fp_line
			(start -0.7874 -0.4064)
			(end -0.7874 0.4064)
			(stroke
				(width 0.1524)
				(type default)
			)
			(layer "B.SilkS")
		)
		(fp_line
			(start 0.7874 0.4064)
			(end 0.7874 -0.4064)
			(stroke
				(width 0.1524)
				(type default)
			)
			(layer "B.SilkS")
		)
		(fp_line
			(start -0.7874 0.4064)
			(end 0.7874 0.4064)
			(stroke
				(width 0.1524)
				(type default)
			)
			(layer "B.SilkS")
		)
		(fp_line
			(start 0.67945 -0.305054)
			(end 0.12065 -0.305054)
			(stroke
				(width 0.1)
				(type default)
			)
			(layer "B.Fab")
		)
		(fp_line
			(start 0.12065 -0.305054)
			(end 0.12065 -0.2794)
			(stroke
				(width 0.1)
				(type default)
			)
			(layer "B.Fab")
		)
		(fp_line
			(start -0.12065 -0.3048)
			(end -0.67945 -0.3048)
			(stroke
				(width 0.1)
				(type default)
			)
			(layer "B.Fab")
		)
		(fp_line
			(start -0.67945 -0.3048)
			(end -0.67945 0.3048)
			(stroke
				(width 0.1)
				(type default)
			)
			(layer "B.Fab")
		)
		(fp_line
			(start 0.12065 -0.2794)
			(end -0.12065 -0.2794)
			(stroke
				(width 0.1)
				(type default)
			)
			(layer "B.Fab")
		)
		(fp_line
			(start -0.12065 -0.2794)
			(end -0.12065 -0.3048)
			(stroke
				(width 0.1)
				(type default)
			)
			(layer "B.Fab")
		)
		(fp_line
			(start 0.12065 0.2794)
			(end 0.12065 0.3048)
			(stroke
				(width 0.1)
				(type default)
			)
			(layer "B.Fab")
		)
		(fp_line
			(start -0.120396 0.2794)
			(end 0.12065 0.2794)
			(stroke
				(width 0.1)
				(type default)
			)
			(layer "B.Fab")
		)
		(fp_line
			(start 0.67945 0.3048)
			(end 0.67945 -0.305054)
			(stroke
				(width 0.1)
				(type default)
			)
			(layer "B.Fab")
		)
		(fp_line
			(start 0.12065 0.3048)
			(end 0.67945 0.3048)
			(stroke
				(width 0.1)
				(type default)
			)
			(layer "B.Fab")
		)
		(fp_line
			(start -0.120396 0.3048)
			(end -0.120396 0.2794)
			(stroke
				(width 0.1)
				(type default)
			)
			(layer "B.Fab")
		)
		(fp_line
			(start -0.67945 0.3048)
			(end -0.120396 0.3048)
			(stroke
				(width 0.1)
				(type default)
			)
			(layer "B.Fab")
		)
		(pad "1" smd circle
			(at 0.40005 0 270)
			(size 0 0)
			(layers "B.Cu" "B.Mask" "B.Paste")
			(net "FM_PCH_SPKR")
		)
		(pad "2" smd circle
			(at -0.40005 0 270)
			(size 0 0)
			(layers "B.Cu" "B.Mask" "B.Paste")
			(net "GND")
		)
	)
)
